(kicad_pcb
	(version 20260206)
	(generator "pcbnew")
	(generator_version "10.0")
	(general
		(thickness 1.6)
		(legacy_teardrops no)
	)
	(paper "A4")
	(title_block
		(title "03242023_DA0F0TMBIJ0_F0T_Motherboard_J_brd_V01_OCP.brd")
		(comment 1 "Grand Teton / footprint 1690 of 6105 (J16), pads 113-224 of 291")
	)
	(layers
		(0 "F.Cu" signal "TOP")
		(4 "In1.Cu" signal "GND")
		(6 "In2.Cu" signal "IN1")
		(8 "In3.Cu" signal "GND1")
		(10 "In4.Cu" signal "IN2")
		(12 "In5.Cu" signal "GND2")
		(14 "In6.Cu" signal "IN3")
		(16 "In7.Cu" signal "GND3")
		(18 "In8.Cu" signal "VCC")
		(20 "In9.Cu" signal "VCC1")
		(22 "In10.Cu" signal "GND4")
		(24 "In11.Cu" signal "IN4")
		(26 "In12.Cu" signal "GND5")
		(28 "In13.Cu" signal "IN5")
		(30 "In14.Cu" signal "GND6")
		(32 "In15.Cu" signal "IN6")
		(34 "In16.Cu" signal "GND7")
		(2 "B.Cu" signal "BOTTOM")
		(9 "F.Adhes" user "F.Adhesive")
		(11 "B.Adhes" user "B.Adhesive")
		(13 "F.Paste" user "Package Geometry/Pastemask Top")
		(15 "B.Paste" user "Package Geometry/Pastemask Bottom")
		(5 "F.SilkS" user "Ref Des/Silkscreen Top")
		(7 "B.SilkS" user "Ref Des/Silkscreen Bottom")
		(1 "F.Mask" user "Board Geometry/Soldermask Top")
		(3 "B.Mask" user "Board Geometry/Soldermask Bottom")
		(17 "Dwgs.User" user "User.Drawings")
		(19 "Cmts.User" user "User.Comments")
		(21 "Eco1.User" user "User.Eco1")
		(23 "Eco2.User" user "User.Eco2")
		(25 "Edge.Cuts" user "Board Geometry/Outline")
		(27 "Margin" user)
		(31 "F.CrtYd" user "Package Geometry/Place Bound Top")
		(29 "B.CrtYd" user "Package Geometry/Place Bound Bottom")
		(35 "F.Fab" user "Ref Des/Assembly Top")
		(33 "B.Fab" user "Ref Des/Assembly Bottom")
	)
	(footprint ""
		(layer "F.Cu")
		(at 454.066148 -258.091686)
		(property "Reference" "J16"
			(at -0.279908 -81.779872 0)
			(unlocked yes)
			(layer "F.SilkS")
			(effects
				(font
					(size 0.7874 0.5842)
					(thickness 0.1524)
				)
				(justify left)
			)
		)
		(property "Value" ""
			(at 0 0 0)
			(layer "F.Fab")
			(effects
				(font
					(size 1.27 1.27)
				)
			)
		)
		(duplicate_pad_numbers_are_jumpers no)
		(pad "113" smd rect
			(at -2.050034 36.975034 270)
			(size 0.519938 1.4986)
			(layers "F.Cu" "F.Mask" "F.Paste")
			(net "M_H_CPU0_SB_DQ<9>")
		)
		(pad "114" smd rect
			(at -2.050034 37.824918 270)
			(size 0.519938 1.4986)
			(layers "F.Cu" "F.Mask" "F.Paste")
			(net "GND")
		)
		(pad "115" smd rect
			(at -2.050034 38.675056 270)
			(size 0.519938 1.4986)
			(layers "F.Cu" "F.Mask" "F.Paste")
			(net "M_H_CPU0_SB_DQS_DP<1>")
		)
		(pad "116" smd rect
			(at -2.050034 39.52494 270)
			(size 0.519938 1.4986)
			(layers "F.Cu" "F.Mask" "F.Paste")
			(net "M_H_CPU0_SB_DQS_DN<1>")
		)
		(pad "117" smd rect
			(at -2.050034 40.375078 270)
			(size 0.519938 1.4986)
			(layers "F.Cu" "F.Mask" "F.Paste")
			(net "GND")
		)
		(pad "118" smd rect
			(at -2.050034 41.224962 270)
			(size 0.519938 1.4986)
			(layers "F.Cu" "F.Mask" "F.Paste")
			(net "M_H_CPU0_SB_DQ<12>")
		)
		(pad "119" smd rect
			(at -2.050034 42.0751 270)
			(size 0.519938 1.4986)
			(layers "F.Cu" "F.Mask" "F.Paste")
			(net "GND")
		)
		(pad "120" smd rect
			(at -2.050034 42.924984 270)
			(size 0.519938 1.4986)
			(layers "F.Cu" "F.Mask" "F.Paste")
			(net "M_H_CPU0_SB_DQ<13>")
		)
		(pad "121" smd rect
			(at -2.050034 43.775122 270)
			(size 0.519938 1.4986)
			(layers "F.Cu" "F.Mask" "F.Paste")
			(net "GND")
		)
		(pad "122" smd rect
			(at -2.050034 44.625006 270)
			(size 0.519938 1.4986)
			(layers "F.Cu" "F.Mask" "F.Paste")
			(net "M_H_CPU0_SB_DQ<16>")
		)
		(pad "123" smd rect
			(at -2.050034 45.47489 270)
			(size 0.519938 1.4986)
			(layers "F.Cu" "F.Mask" "F.Paste")
			(net "GND")
		)
		(pad "124" smd rect
			(at -2.050034 46.325028 270)
			(size 0.519938 1.4986)
			(layers "F.Cu" "F.Mask" "F.Paste")
			(net "M_H_CPU0_SB_DQ<17>")
		)
		(pad "125" smd rect
			(at -2.050034 47.174912 270)
			(size 0.519938 1.4986)
			(layers "F.Cu" "F.Mask" "F.Paste")
			(net "GND")
		)
		(pad "126" smd rect
			(at -2.050034 48.02505 270)
			(size 0.519938 1.4986)
			(layers "F.Cu" "F.Mask" "F.Paste")
			(net "M_H_CPU0_SB_DQS_DP<2>")
		)
		(pad "127" smd rect
			(at -2.050034 48.874934 270)
			(size 0.519938 1.4986)
			(layers "F.Cu" "F.Mask" "F.Paste")
			(net "M_H_CPU0_SB_DQS_DN<2>")
		)
		(pad "128" smd rect
			(at -2.050034 49.725072 270)
			(size 0.519938 1.4986)
			(layers "F.Cu" "F.Mask" "F.Paste")
			(net "GND")
		)
		(pad "129" smd rect
			(at -2.050034 50.574956 270)
			(size 0.519938 1.4986)
			(layers "F.Cu" "F.Mask" "F.Paste")
			(net "M_H_CPU0_SB_DQ<20>")
		)
		(pad "130" smd rect
			(at -2.050034 51.425094 270)
			(size 0.519938 1.4986)
			(layers "F.Cu" "F.Mask" "F.Paste")
			(net "GND")
		)
		(pad "131" smd rect
			(at -2.050034 52.274978 270)
			(size 0.519938 1.4986)
			(layers "F.Cu" "F.Mask" "F.Paste")
			(net "M_H_CPU0_SB_DQ<21>")
		)
		(pad "132" smd rect
			(at -2.050034 53.125116 270)
			(size 0.519938 1.4986)
			(layers "F.Cu" "F.Mask" "F.Paste")
			(net "GND")
		)
		(pad "133" smd rect
			(at -2.050034 53.975 270)
			(size 0.519938 1.4986)
			(layers "F.Cu" "F.Mask" "F.Paste")
			(net "M_H_CPU0_SB_DQ<24>")
		)
		(pad "134" smd rect
			(at -2.050034 54.824884 270)
			(size 0.519938 1.4986)
			(layers "F.Cu" "F.Mask" "F.Paste")
			(net "GND")
		)
		(pad "135" smd rect
			(at -2.050034 55.675022 270)
			(size 0.519938 1.4986)
			(layers "F.Cu" "F.Mask" "F.Paste")
			(net "M_H_CPU0_SB_DQ<25>")
		)
		(pad "136" smd rect
			(at -2.050034 56.524906 270)
			(size 0.519938 1.4986)
			(layers "F.Cu" "F.Mask" "F.Paste")
			(net "GND")
		)
		(pad "137" smd rect
			(at -2.050034 57.375044 270)
			(size 0.519938 1.4986)
			(layers "F.Cu" "F.Mask" "F.Paste")
			(net "M_H_CPU0_SB_DQS_DP<3>")
		)
		(pad "138" smd rect
			(at -2.050034 58.224928 270)
			(size 0.519938 1.4986)
			(layers "F.Cu" "F.Mask" "F.Paste")
			(net "M_H_CPU0_SB_DQS_DN<3>")
		)
		(pad "139" smd rect
			(at -2.050034 59.075066 270)
			(size 0.519938 1.4986)
			(layers "F.Cu" "F.Mask" "F.Paste")
			(net "GND")
		)
		(pad "140" smd rect
			(at -2.050034 59.92495 270)
			(size 0.519938 1.4986)
			(layers "F.Cu" "F.Mask" "F.Paste")
			(net "M_H_CPU0_SB_DQ<28>")
		)
		(pad "141" smd rect
			(at -2.050034 60.775088 270)
			(size 0.519938 1.4986)
			(layers "F.Cu" "F.Mask" "F.Paste")
			(net "GND")
		)
		(pad "142" smd rect
			(at -2.050034 61.624972 270)
			(size 0.519938 1.4986)
			(layers "F.Cu" "F.Mask" "F.Paste")
			(net "M_H_CPU0_SB_DQ<29>")
		)
		(pad "143" smd rect
			(at -2.050034 62.47511 270)
			(size 0.519938 1.4986)
			(layers "F.Cu" "F.Mask" "F.Paste")
			(net "GND")
		)
		(pad "144" smd rect
			(at -2.050034 63.324994 270)
			(size 0.519938 1.4986)
			(layers "F.Cu" "F.Mask" "F.Paste")
			(net "TP_CHH_CPU0_DIMM2_FRU_1")
		)
		(pad "145" smd rect
			(at 2.050034 -63.324994 270)
			(size 0.519938 1.4986)
			(layers "F.Cu" "F.Mask" "F.Paste")
			(net "P12V_S3_AUX_CPU0_NVDIMM")
		)
		(pad "146" smd rect
			(at 2.050034 -62.47511 270)
			(size 0.519938 1.4986)
			(layers "F.Cu" "F.Mask" "F.Paste")
			(net "P12V_S3_AUX_CPU0_NVDIMM")
		)
		(pad "147" smd rect
			(at 2.050034 -61.624972 270)
			(size 0.519938 1.4986)
			(layers "F.Cu" "F.Mask" "F.Paste")
			(net "PWRGD_CHH_CPU0_DIMM2")
		)
		(pad "148" smd rect
			(at 2.050034 -60.775088 270)
			(size 0.519938 1.4986)
			(layers "F.Cu" "F.Mask" "F.Paste")
			(net "PD_CHH_CPU0_DIMM2_SAA")
		)
		(pad "149" smd rect
			(at 2.050034 -59.92495 270)
			(size 0.519938 1.4986)
			(layers "F.Cu" "F.Mask" "F.Paste")
			(net "TP_CHH_CPU0_DIMM2_FRU_2")
		)
		(pad "150" smd rect
			(at 2.050034 -59.075066 270)
			(size 0.519938 1.4986)
			(layers "F.Cu" "F.Mask" "F.Paste")
			(net "TP_CHH_CPU0_DIMM2_FRU_3")
		)
		(pad "151" smd rect
			(at 2.050034 -58.224928 270)
			(size 0.519938 1.4986)
			(layers "F.Cu" "F.Mask" "F.Paste")
			(net "GND")
		)
		(pad "152" smd rect
			(at 2.050034 -57.375044 270)
			(size 0.519938 1.4986)
			(layers "F.Cu" "F.Mask" "F.Paste")
			(net "M_H_CPU0_SA_DQ<2>")
		)
		(pad "153" smd rect
			(at 2.050034 -56.524906 270)
			(size 0.519938 1.4986)
			(layers "F.Cu" "F.Mask" "F.Paste")
			(net "GND")
		)
		(pad "154" smd rect
			(at 2.050034 -55.675022 270)
			(size 0.519938 1.4986)
			(layers "F.Cu" "F.Mask" "F.Paste")
			(net "M_H_CPU0_SA_DQ<3>")
		)
		(pad "155" smd rect
			(at 2.050034 -54.824884 270)
			(size 0.519938 1.4986)
			(layers "F.Cu" "F.Mask" "F.Paste")
			(net "GND")
		)
		(pad "156" smd rect
			(at 2.050034 -53.975 270)
			(size 0.519938 1.4986)
			(layers "F.Cu" "F.Mask" "F.Paste")
			(net "M_H_CPU0_SA_DQS_DN<5>")
		)
		(pad "157" smd rect
			(at 2.050034 -53.125116 270)
			(size 0.519938 1.4986)
			(layers "F.Cu" "F.Mask" "F.Paste")
			(net "M_H_CPU0_SA_DQS_DP<5>")
		)
		(pad "158" smd rect
			(at 2.050034 -52.274978 270)
			(size 0.519938 1.4986)
			(layers "F.Cu" "F.Mask" "F.Paste")
			(net "GND")
		)
		(pad "159" smd rect
			(at 2.050034 -51.425094 270)
			(size 0.519938 1.4986)
			(layers "F.Cu" "F.Mask" "F.Paste")
			(net "M_H_CPU0_SA_DQ<6>")
		)
		(pad "160" smd rect
			(at 2.050034 -50.574956 270)
			(size 0.519938 1.4986)
			(layers "F.Cu" "F.Mask" "F.Paste")
			(net "GND")
		)
		(pad "161" smd rect
			(at 2.050034 -49.725072 270)
			(size 0.519938 1.4986)
			(layers "F.Cu" "F.Mask" "F.Paste")
			(net "M_H_CPU0_SA_DQ<7>")
		)
		(pad "162" smd rect
			(at 2.050034 -48.874934 270)
			(size 0.519938 1.4986)
			(layers "F.Cu" "F.Mask" "F.Paste")
			(net "GND")
		)
		(pad "163" smd rect
			(at 2.050034 -48.02505 270)
			(size 0.519938 1.4986)
			(layers "F.Cu" "F.Mask" "F.Paste")
			(net "M_H_CPU0_SA_DQ<10>")
		)
		(pad "164" smd rect
			(at 2.050034 -47.174912 270)
			(size 0.519938 1.4986)
			(layers "F.Cu" "F.Mask" "F.Paste")
			(net "GND")
		)
		(pad "165" smd rect
			(at 2.050034 -46.325028 270)
			(size 0.519938 1.4986)
			(layers "F.Cu" "F.Mask" "F.Paste")
			(net "M_H_CPU0_SA_DQ<11>")
		)
		(pad "166" smd rect
			(at 2.050034 -45.47489 270)
			(size 0.519938 1.4986)
			(layers "F.Cu" "F.Mask" "F.Paste")
			(net "GND")
		)
		(pad "167" smd rect
			(at 2.050034 -44.625006 270)
			(size 0.519938 1.4986)
			(layers "F.Cu" "F.Mask" "F.Paste")
			(net "M_H_CPU0_SA_DQS_DN<6>")
		)
		(pad "168" smd rect
			(at 2.050034 -43.775122 270)
			(size 0.519938 1.4986)
			(layers "F.Cu" "F.Mask" "F.Paste")
			(net "M_H_CPU0_SA_DQS_DP<6>")
		)
		(pad "169" smd rect
			(at 2.050034 -42.924984 270)
			(size 0.519938 1.4986)
			(layers "F.Cu" "F.Mask" "F.Paste")
			(net "GND")
		)
		(pad "170" smd rect
			(at 2.050034 -42.0751 270)
			(size 0.519938 1.4986)
			(layers "F.Cu" "F.Mask" "F.Paste")
			(net "M_H_CPU0_SA_DQ<14>")
		)
		(pad "171" smd rect
			(at 2.050034 -41.224962 270)
			(size 0.519938 1.4986)
			(layers "F.Cu" "F.Mask" "F.Paste")
			(net "GND")
		)
		(pad "172" smd rect
			(at 2.050034 -40.375078 270)
			(size 0.519938 1.4986)
			(layers "F.Cu" "F.Mask" "F.Paste")
			(net "M_H_CPU0_SA_DQ<15>")
		)
		(pad "173" smd rect
			(at 2.050034 -39.52494 270)
			(size 0.519938 1.4986)
			(layers "F.Cu" "F.Mask" "F.Paste")
			(net "GND")
		)
		(pad "174" smd rect
			(at 2.050034 -38.675056 270)
			(size 0.519938 1.4986)
			(layers "F.Cu" "F.Mask" "F.Paste")
			(net "M_H_CPU0_SA_DQ<18>")
		)
		(pad "175" smd rect
			(at 2.050034 -37.824918 270)
			(size 0.519938 1.4986)
			(layers "F.Cu" "F.Mask" "F.Paste")
			(net "GND")
		)
		(pad "176" smd rect
			(at 2.050034 -36.975034 270)
			(size 0.519938 1.4986)
			(layers "F.Cu" "F.Mask" "F.Paste")
			(net "M_H_CPU0_SA_DQ<19>")
		)
		(pad "177" smd rect
			(at 2.050034 -36.124896 270)
			(size 0.519938 1.4986)
			(layers "F.Cu" "F.Mask" "F.Paste")
			(net "GND")
		)
		(pad "178" smd rect
			(at 2.050034 -35.275012 270)
			(size 0.519938 1.4986)
			(layers "F.Cu" "F.Mask" "F.Paste")
			(net "M_H_CPU0_SA_DQS_DN<7>")
		)
		(pad "179" smd rect
			(at 2.050034 -34.425128 270)
			(size 0.519938 1.4986)
			(layers "F.Cu" "F.Mask" "F.Paste")
			(net "M_H_CPU0_SA_DQS_DP<7>")
		)
		(pad "180" smd rect
			(at 2.050034 -33.57499 270)
			(size 0.519938 1.4986)
			(layers "F.Cu" "F.Mask" "F.Paste")
			(net "GND")
		)
		(pad "181" smd rect
			(at 2.050034 -32.725106 270)
			(size 0.519938 1.4986)
			(layers "F.Cu" "F.Mask" "F.Paste")
			(net "M_H_CPU0_SA_DQ<22>")
		)
		(pad "182" smd rect
			(at 2.050034 -31.874968 270)
			(size 0.519938 1.4986)
			(layers "F.Cu" "F.Mask" "F.Paste")
			(net "GND")
		)
		(pad "183" smd rect
			(at 2.050034 -31.025084 270)
			(size 0.519938 1.4986)
			(layers "F.Cu" "F.Mask" "F.Paste")
			(net "M_H_CPU0_SA_DQ<23>")
		)
		(pad "184" smd rect
			(at 2.050034 -30.174946 270)
			(size 0.519938 1.4986)
			(layers "F.Cu" "F.Mask" "F.Paste")
			(net "GND")
		)
		(pad "185" smd rect
			(at 2.050034 -29.325062 270)
			(size 0.519938 1.4986)
			(layers "F.Cu" "F.Mask" "F.Paste")
			(net "M_H_CPU0_SA_DQ<26>")
		)
		(pad "186" smd rect
			(at 2.050034 -28.474924 270)
			(size 0.519938 1.4986)
			(layers "F.Cu" "F.Mask" "F.Paste")
			(net "GND")
		)
		(pad "187" smd rect
			(at 2.050034 -27.62504 270)
			(size 0.519938 1.4986)
			(layers "F.Cu" "F.Mask" "F.Paste")
			(net "M_H_CPU0_SA_DQ<27>")
		)
		(pad "188" smd rect
			(at 2.050034 -26.774902 270)
			(size 0.519938 1.4986)
			(layers "F.Cu" "F.Mask" "F.Paste")
			(net "GND")
		)
		(pad "189" smd rect
			(at 2.050034 -25.925018 270)
			(size 0.519938 1.4986)
			(layers "F.Cu" "F.Mask" "F.Paste")
			(net "M_H_CPU0_SA_DQS_DN<8>")
		)
		(pad "190" smd rect
			(at 2.050034 -25.07488 270)
			(size 0.519938 1.4986)
			(layers "F.Cu" "F.Mask" "F.Paste")
			(net "M_H_CPU0_SA_DQS_DP<8>")
		)
		(pad "191" smd rect
			(at 2.050034 -24.224996 270)
			(size 0.519938 1.4986)
			(layers "F.Cu" "F.Mask" "F.Paste")
			(net "GND")
		)
		(pad "192" smd rect
			(at 2.050034 -23.375112 270)
			(size 0.519938 1.4986)
			(layers "F.Cu" "F.Mask" "F.Paste")
			(net "M_H_CPU0_SA_DQ<30>")
		)
		(pad "193" smd rect
			(at 2.050034 -22.524974 270)
			(size 0.519938 1.4986)
			(layers "F.Cu" "F.Mask" "F.Paste")
			(net "GND")
		)
		(pad "194" smd rect
			(at 2.050034 -21.67509 270)
			(size 0.519938 1.4986)
			(layers "F.Cu" "F.Mask" "F.Paste")
			(net "M_H_CPU0_SA_DQ<31>")
		)
		(pad "195" smd rect
			(at 2.050034 -20.824952 270)
			(size 0.519938 1.4986)
			(layers "F.Cu" "F.Mask" "F.Paste")
			(net "GND")
		)
		(pad "196" smd rect
			(at 2.050034 -19.975068 270)
			(size 0.519938 1.4986)
			(layers "F.Cu" "F.Mask" "F.Paste")
			(net "M_H_CPU0_SA_CB<2>")
		)
		(pad "197" smd rect
			(at 2.050034 -19.12493 270)
			(size 0.519938 1.4986)
			(layers "F.Cu" "F.Mask" "F.Paste")
			(net "GND")
		)
		(pad "198" smd rect
			(at 2.050034 -18.275046 270)
			(size 0.519938 1.4986)
			(layers "F.Cu" "F.Mask" "F.Paste")
			(net "M_H_CPU0_SA_CB<3>")
		)
		(pad "199" smd rect
			(at 2.050034 -17.424908 270)
			(size 0.519938 1.4986)
			(layers "F.Cu" "F.Mask" "F.Paste")
			(net "GND")
		)
		(pad "200" smd rect
			(at 2.050034 -16.575024 270)
			(size 0.519938 1.4986)
			(layers "F.Cu" "F.Mask" "F.Paste")
			(net "M_H_CPU0_SA_DQS_DN<9>")
		)
		(pad "201" smd rect
			(at 2.050034 -15.724886 270)
			(size 0.519938 1.4986)
			(layers "F.Cu" "F.Mask" "F.Paste")
			(net "M_H_CPU0_SA_DQS_DP<9>")
		)
		(pad "202" smd rect
			(at 2.050034 -14.875002 270)
			(size 0.519938 1.4986)
			(layers "F.Cu" "F.Mask" "F.Paste")
			(net "GND")
		)
		(pad "203" smd rect
			(at 2.050034 -14.025118 270)
			(size 0.519938 1.4986)
			(layers "F.Cu" "F.Mask" "F.Paste")
			(net "M_H_CPU0_SA_CB<6>")
		)
		(pad "204" smd rect
			(at 2.050034 -13.17498 270)
			(size 0.519938 1.4986)
			(layers "F.Cu" "F.Mask" "F.Paste")
			(net "GND")
		)
		(pad "205" smd rect
			(at 2.050034 -12.325096 270)
			(size 0.519938 1.4986)
			(layers "F.Cu" "F.Mask" "F.Paste")
			(net "M_H_CPU0_SA_CB<7>")
		)
		(pad "206" smd rect
			(at 2.050034 -11.474958 270)
			(size 0.519938 1.4986)
			(layers "F.Cu" "F.Mask" "F.Paste")
			(net "GND")
		)
		(pad "207" smd rect
			(at 2.050034 -10.625074 270)
			(size 0.519938 1.4986)
			(layers "F.Cu" "F.Mask" "F.Paste")
			(net "RST_M_GH_CPU0_FPGA_N")
		)
		(pad "208" smd rect
			(at 2.050034 -9.774936 270)
			(size 0.519938 1.4986)
			(layers "F.Cu" "F.Mask" "F.Paste")
			(net "GND")
		)
		(pad "209" smd rect
			(at 2.050034 -8.925052 270)
			(size 0.519938 1.4986)
			(layers "F.Cu" "F.Mask" "F.Paste")
			(net "M_H_CPU0_SA_CS_N<3>")
		)
		(pad "210" smd rect
			(at 2.050034 -8.074914 270)
			(size 0.519938 1.4986)
			(layers "F.Cu" "F.Mask" "F.Paste")
			(net "GND")
		)
		(pad "211" smd rect
			(at 2.050034 -7.22503 270)
			(size 0.519938 1.4986)
			(layers "F.Cu" "F.Mask" "F.Paste")
			(net "M_H_CPU0_SA_CA<1>")
		)
		(pad "212" smd rect
			(at 2.050034 -6.374892 270)
			(size 0.519938 1.4986)
			(layers "F.Cu" "F.Mask" "F.Paste")
			(net "GND")
		)
		(pad "213" smd rect
			(at 2.050034 -5.525008 270)
			(size 0.519938 1.4986)
			(layers "F.Cu" "F.Mask" "F.Paste")
			(net "M_H_CPU0_SA_CA<3>")
		)
		(pad "214" smd rect
			(at 2.050034 -4.675124 270)
			(size 0.519938 1.4986)
			(layers "F.Cu" "F.Mask" "F.Paste")
			(net "GND")
		)
		(pad "215" smd rect
			(at 2.050034 -3.824986 270)
			(size 0.519938 1.4986)
			(layers "F.Cu" "F.Mask" "F.Paste")
			(net "M_H_CPU0_SA_CA<5>")
		)
		(pad "216" smd rect
			(at 2.050034 -2.975102 270)
			(size 0.519938 1.4986)
			(layers "F.Cu" "F.Mask" "F.Paste")
			(net "GND")
		)
		(pad "217" smd rect
			(at 2.050034 -2.124964 270)
			(size 0.519938 1.4986)
			(layers "F.Cu" "F.Mask" "F.Paste")
			(net "M_H_CPU0_CLK_DP<1>")
		)
		(pad "218" smd rect
			(at 2.050034 -1.27508 270)
			(size 0.519938 1.4986)
			(layers "F.Cu" "F.Mask" "F.Paste")
			(net "M_H_CPU0_CLK_DN<1>")
		)
		(pad "219" smd rect
			(at 2.050034 -0.424942 270)
			(size 0.519938 1.4986)
			(layers "F.Cu" "F.Mask" "F.Paste")
			(net "GND")
		)
		(pad "220" smd rect
			(at 2.050034 5.525008 270)
			(size 0.519938 1.4986)
			(layers "F.Cu" "F.Mask" "F.Paste")
			(net "TP_CHH_CPU0_DIMM2_FRU_4")
		)
		(pad "221" smd rect
			(at 2.050034 6.374892 270)
			(size 0.519938 1.4986)
			(layers "F.Cu" "F.Mask" "F.Paste")
			(net "M_H_CPU0_SB_CA<1>")
		)
		(pad "222" smd rect
			(at 2.050034 7.22503 270)
			(size 0.519938 1.4986)
			(layers "F.Cu" "F.Mask" "F.Paste")
			(net "GND")
		)
		(pad "223" smd rect
			(at 2.050034 8.074914 270)
			(size 0.519938 1.4986)
			(layers "F.Cu" "F.Mask" "F.Paste")
			(net "M_H_CPU0_SB_CA<3>")
		)
		(pad "224" smd rect
			(at 2.050034 8.925052 270)
			(size 0.519938 1.4986)
			(layers "F.Cu" "F.Mask" "F.Paste")
			(net "GND")
		)
	)
)
